(kicad_pcb
	(version 20260206)
	(generator "pcbnew")
	(generator_version "10.0")
	(general
		(thickness 1.6)
		(legacy_teardrops no)
	)
	(paper "A4")
	(title_block
		(title "Bryce Canyon_F.DPB_16315-1-OCP.brd")
		(comment 1 "Bryce Canyon / footprints 254-260 of 2223")
	)
	(layers
		(0 "F.Cu" signal "TOP")
		(4 "In1.Cu" signal "L2GND")
		(6 "In2.Cu" signal "L3")
		(8 "In3.Cu" signal "L4GND")
		(10 "In4.Cu" signal "L5")
		(12 "In5.Cu" signal "L6VCC")
		(14 "In6.Cu" signal "L7VCC")
		(16 "In7.Cu" signal "L8")
		(18 "In8.Cu" signal "L9GND")
		(20 "In9.Cu" signal "L10")
		(22 "In10.Cu" signal "L11GND")
		(2 "B.Cu" signal "BOTTOM")
		(9 "F.Adhes" user "F.Adhesive")
		(11 "B.Adhes" user "B.Adhesive")
		(13 "F.Paste" user "Package Geometry/Pastemask Top")
		(15 "B.Paste" user "Package Geometry/Pastemask Bottom")
		(5 "F.SilkS" user "Ref Des/Silkscreen Top")
		(7 "B.SilkS" user "Ref Des/Silkscreen Bottom")
		(1 "F.Mask" user "Board Geometry/Soldermask Top")
		(3 "B.Mask" user "Board Geometry/Soldermask Bottom")
		(17 "Dwgs.User" user "User.Drawings")
		(19 "Cmts.User" user "User.Comments")
		(21 "Eco1.User" user "User.Eco1")
		(23 "Eco2.User" user "User.Eco2")
		(25 "Edge.Cuts" user "Board Geometry/Outline")
		(27 "Margin" user)
		(31 "F.CrtYd" user "Package Geometry/Place Bound Top")
		(29 "B.CrtYd" user "Package Geometry/Place Bound Bottom")
		(35 "F.Fab" user "Ref Des/Assembly Top")
		(33 "B.Fab" user "Ref Des/Assembly Bottom")
	)
	(footprint ""
		(layer "F.Cu")
		(at 333.501746 -28.98775)
		(property "Reference" "C20"
			(at 0 0 0)
			(layer "F.SilkS")
			(hide yes)
			(effects
				(font
					(size 1.27 1.27)
				)
			)
		)
		(property "Value" "SC1U16V3KX-5GP"
			(at 0 -2.8194 0)
			(unlocked yes)
			(layer "F.Fab")
			(hide yes)
			(effects
				(font
					(size 1.016 1.016)
					(thickness 0.1524)
				)
			)
		)
		(property "Device Type" "C603H36"
			(at 0 -4.3434 0)
			(unlocked yes)
			(layer "F.Fab")
			(hide yes)
			(effects
				(font
					(size 1.016 1.016)
					(thickness 0.1524)
				)
			)
		)
		(duplicate_pad_numbers_are_jumpers no)
		(fp_line
			(start 0.508 0)
			(end -0.508 0)
			(stroke
				(width 0.2032)
				(type default)
			)
			(layer "F.SilkS")
		)
		(fp_rect
			(start -0.5842 1.3335)
			(end 0.5842 -1.3335)
			(stroke
				(width 0)
				(type default)
			)
			(fill no)
			(layer "F.CrtYd")
		)
		(fp_rect
			(start -0.5842 1.3335)
			(end 0.5842 -1.3335)
			(stroke
				(width 0)
				(type default)
			)
			(fill no)
			(layer "F.Fab")
		)
		(pad "1" smd custom
			(at 0 -0.762)
			(size 0.2159 0.2159)
			(layers "F.Cu" "F.Mask" "F.Paste")
			(net "P3V3_STBY_B")
			(options
				(clearance outline)
				(anchor circle)
			)
			(primitives
				(gr_poly
					(pts
						(arc
							(start -0.3302 -0.4318)
							(mid -0.402042 -0.402042)
							(end -0.4318 -0.3302)
						)
						(arc
							(start -0.4318 0.3302)
							(mid -0.402042 0.402042)
							(end -0.3302 0.4318)
						)
						(arc
							(start 0.3302 0.4318)
							(mid 0.402042 0.402042)
							(end 0.4318 0.3302)
						)
						(arc
							(start 0.4318 -0.3302)
							(mid 0.402042 -0.402042)
							(end 0.3302 -0.4318)
						)
					)
					(width 0)
					(fill yes)
				)
			)
		)
		(pad "2" smd custom
			(at 0 0.762)
			(size 0.2159 0.2159)
			(layers "F.Cu" "F.Mask" "F.Paste")
			(net "GND")
			(options
				(clearance outline)
				(anchor circle)
			)
			(primitives
				(gr_poly
					(pts
						(arc
							(start -0.3302 -0.4318)
							(mid -0.402042 -0.402042)
							(end -0.4318 -0.3302)
						)
						(arc
							(start -0.4318 0.3302)
							(mid -0.402042 0.402042)
							(end -0.3302 0.4318)
						)
						(arc
							(start 0.3302 0.4318)
							(mid 0.402042 0.402042)
							(end 0.4318 0.3302)
						)
						(arc
							(start 0.4318 -0.3302)
							(mid 0.402042 -0.402042)
							(end 0.3302 -0.4318)
						)
					)
					(width 0)
					(fill yes)
				)
			)
		)
	)
	(footprint ""
		(layer "F.Cu")
		(at 377.788932 -283.957522 90)
		(property "Reference" "R580"
			(at 0 0 90)
			(layer "F.SilkS")
			(hide yes)
			(effects
				(font
					(size 1.27 1.27)
				)
			)
		)
		(property "Value" "4K7R2J-2-GP"
			(at 0.064008 -3.993896 90)
			(unlocked yes)
			(layer "F.Fab")
			(hide yes)
			(effects
				(font
					(size 1.016 1.016)
					(thickness 0.1524)
				)
			)
		)
		(property "Device Type" "R402H16"
			(at 0.064008 -5.517896 90)
			(unlocked yes)
			(layer "F.Fab")
			(hide yes)
			(effects
				(font
					(size 1.016 1.016)
					(thickness 0.1524)
				)
			)
		)
		(duplicate_pad_numbers_are_jumpers no)
		(fp_line
			(start 0.508 -0.9398)
			(end -0.508 -0.9398)
			(stroke
				(width 0.1524)
				(type default)
			)
			(layer "F.SilkS")
		)
		(fp_line
			(start -0.508 -0.9398)
			(end -0.508 0.9398)
			(stroke
				(width 0.1524)
				(type default)
			)
			(layer "F.SilkS")
		)
		(fp_rect
			(start -0.508 0.9398)
			(end 0.508 -0.9398)
			(stroke
				(width 0)
				(type default)
			)
			(fill no)
			(layer "F.CrtYd")
		)
		(fp_rect
			(start -0.508 0.9398)
			(end 0.508 -0.9398)
			(stroke
				(width 0)
				(type default)
			)
			(fill no)
			(layer "F.Fab")
		)
		(pad "1" smd custom
			(at 0 -0.4445 90)
			(size 0.1397 0.1397)
			(layers "F.Cu" "F.Mask" "F.Paste")
			(net "DRIVE_B_32_ACT")
			(options
				(clearance outline)
				(anchor circle)
			)
			(primitives
				(gr_poly
					(pts
						(arc
							(start -0.1778 -0.2794)
							(mid -0.249642 -0.249642)
							(end -0.2794 -0.1778)
						)
						(arc
							(start -0.2794 0.1778)
							(mid -0.249642 0.249642)
							(end -0.1778 0.2794)
						)
						(arc
							(start 0.1778 0.2794)
							(mid 0.249642 0.249642)
							(end 0.2794 0.1778)
						)
						(arc
							(start 0.2794 -0.1778)
							(mid 0.249642 -0.249642)
							(end 0.1778 -0.2794)
						)
					)
					(width 0)
					(fill yes)
				)
			)
		)
		(pad "2" smd custom
			(at 0 0.4445 90)
			(size 0.1397 0.1397)
			(layers "F.Cu" "F.Mask" "F.Paste")
			(net "GND")
			(options
				(clearance outline)
				(anchor circle)
			)
			(primitives
				(gr_poly
					(pts
						(arc
							(start -0.1778 -0.2794)
							(mid -0.249642 -0.249642)
							(end -0.2794 -0.1778)
						)
						(arc
							(start -0.2794 0.1778)
							(mid -0.249642 0.249642)
							(end -0.1778 0.2794)
						)
						(arc
							(start 0.1778 0.2794)
							(mid 0.249642 0.249642)
							(end 0.2794 0.1778)
						)
						(arc
							(start 0.2794 -0.1778)
							(mid 0.249642 -0.249642)
							(end 0.1778 -0.2794)
						)
					)
					(width 0)
					(fill yes)
				)
			)
		)
	)
	(footprint ""
		(layer "F.Cu")
		(at 236.601 -395.9098 180)
		(property "Reference" "C584"
			(at 0 0 180)
			(layer "F.SilkS")
			(hide yes)
			(effects
				(font
					(size 1.27 1.27)
				)
			)
		)
		(property "Value" "SCD22U16V2KX-GP"
			(at 1.1811 -2.7051 180)
			(unlocked yes)
			(layer "F.Fab")
			(hide yes)
			(effects
				(font
					(size 1.016 1.016)
					(thickness 0.1524)
				)
			)
		)
		(property "Device Type" "C402H22"
			(at 1.1811 -4.2291 180)
			(unlocked yes)
			(layer "F.Fab")
			(hide yes)
			(effects
				(font
					(size 1.016 1.016)
					(thickness 0.1524)
				)
			)
		)
		(duplicate_pad_numbers_are_jumpers no)
		(fp_rect
			(start -0.4318 0.9525)
			(end 0.4318 -0.9525)
			(stroke
				(width 0)
				(type default)
			)
			(fill no)
			(layer "F.CrtYd")
		)
		(fp_rect
			(start -0.4318 0.9525)
			(end 0.4318 -0.9525)
			(stroke
				(width 0)
				(type default)
			)
			(fill no)
			(layer "F.Fab")
		)
		(pad "1" smd custom
			(at 0 -0.4445 180)
			(size 0.1524 0.1524)
			(layers "F.Cu" "F.Mask" "F.Paste")
			(net "MB3_TIME_R")
			(options
				(clearance outline)
				(anchor circle)
			)
			(primitives
				(gr_poly
					(pts
						(arc
							(start 0.3048 -0.2032)
							(mid 0.275042 -0.275042)
							(end 0.2032 -0.3048)
						)
						(arc
							(start -0.2032 -0.3048)
							(mid -0.275042 -0.275042)
							(end -0.3048 -0.2032)
						)
						(arc
							(start -0.3048 0.2032)
							(mid -0.275042 0.275042)
							(end -0.2032 0.3048)
						)
						(arc
							(start 0.2032 0.3048)
							(mid 0.275042 0.275042)
							(end 0.3048 0.2032)
						)
					)
					(width 0)
					(fill yes)
				)
			)
		)
		(pad "2" smd custom
			(at 0 0.4445 180)
			(size 0.1524 0.1524)
			(layers "F.Cu" "F.Mask" "F.Paste")
			(net "AGND_CURRENT_DPB")
			(options
				(clearance outline)
				(anchor circle)
			)
			(primitives
				(gr_poly
					(pts
						(arc
							(start 0.3048 -0.2032)
							(mid 0.275042 -0.275042)
							(end 0.2032 -0.3048)
						)
						(arc
							(start -0.2032 -0.3048)
							(mid -0.275042 -0.275042)
							(end -0.3048 -0.2032)
						)
						(arc
							(start -0.3048 0.2032)
							(mid -0.275042 0.275042)
							(end -0.2032 0.3048)
						)
						(arc
							(start 0.2032 0.3048)
							(mid 0.275042 0.275042)
							(end 0.3048 0.2032)
						)
					)
					(width 0)
					(fill yes)
				)
			)
		)
	)
	(footprint ""
		(layer "F.Cu")
		(at 174.625 -46.649894 180)
		(property "Reference" "D29"
			(at 0 0 180)
			(layer "F.SilkS")
			(hide yes)
			(effects
				(font
					(size 1.27 1.27)
				)
			)
		)
		(property "Value" "RB551V30-GP"
			(at 0 -6.7818 180)
			(unlocked yes)
			(layer "F.Fab")
			(hide yes)
			(effects
				(font
					(size 1.016 1.016)
					(thickness 0.1524)
				)
			)
		)
		(property "Device Type" "SOD323AKH38"
			(at 0 -8.6868 180)
			(unlocked yes)
			(layer "F.Fab")
			(hide yes)
			(effects
				(font
					(size 1.016 1.016)
					(thickness 0.1524)
				)
			)
		)
		(duplicate_pad_numbers_are_jumpers no)
		(fp_line
			(start 0.889 2.159)
			(end -0.889 2.159)
			(stroke
				(width 0.1524)
				(type default)
			)
			(layer "F.SilkS")
		)
		(fp_line
			(start 0.889 -1.9304)
			(end 0.889 2.159)
			(stroke
				(width 0.1524)
				(type default)
			)
			(layer "F.SilkS")
		)
		(fp_line
			(start 0.762 2.0574)
			(end -0.762 2.0574)
			(stroke
				(width 0.508)
				(type default)
			)
			(layer "F.SilkS")
		)
		(fp_line
			(start -0.889 2.159)
			(end -0.889 -1.9304)
			(stroke
				(width 0.1524)
				(type default)
			)
			(layer "F.SilkS")
		)
		(fp_line
			(start -0.889 -1.9304)
			(end 0.889 -1.9304)
			(stroke
				(width 0.1524)
				(type default)
			)
			(layer "F.SilkS")
		)
		(fp_rect
			(start -1.016 2.3114)
			(end 1.016 -2.0066)
			(stroke
				(width 0)
				(type default)
			)
			(fill no)
			(layer "F.CrtYd")
		)
		(fp_poly
			(pts
				(xy -1.016 -2.0066) (xy 1.016 -2.0066) (xy 1.016 2.3114) (xy -1.016 2.3114)
			)
			(stroke
				(width 0)
				(type default)
			)
			(fill no)
			(layer "F.Fab")
		)
		(pad "A" smd rect
			(at 0 -1.143 180)
			(size 0.5588 1.016)
			(layers "F.Cu" "F.Mask" "F.Paste")
			(net "SW_HDD_R29")
		)
		(pad "K" smd rect
			(at 0 1.143 180)
			(size 0.5588 1.016)
			(layers "F.Cu" "F.Mask" "F.Paste")
			(net "SW_HDD_N29")
		)
	)
	(footprint ""
		(layer "F.Cu")
		(at 135.7249 -127.254)
		(property "Reference" "R300"
			(at 0 0 0)
			(layer "F.SilkS")
			(hide yes)
			(effects
				(font
					(size 1.27 1.27)
				)
			)
		)
		(property "Value" "130R3F-GP"
			(at -0.0254 -2.5146 0)
			(unlocked yes)
			(layer "F.Fab")
			(hide yes)
			(effects
				(font
					(size 1.016 1.016)
					(thickness 0.1524)
				)
			)
		)
		(property "Device Type" "R603H22"
			(at -0.0254 -4.0386 0)
			(unlocked yes)
			(layer "F.Fab")
			(hide yes)
			(effects
				(font
					(size 1.016 1.016)
					(thickness 0.1524)
				)
			)
		)
		(duplicate_pad_numbers_are_jumpers no)
		(fp_line
			(start -0.4826 0)
			(end -0.2032 0)
			(stroke
				(width 0.2032)
				(type default)
			)
			(layer "F.SilkS")
		)
		(fp_line
			(start 0.2032 0)
			(end 0.4826 0)
			(stroke
				(width 0.2032)
				(type default)
			)
			(layer "F.SilkS")
		)
		(fp_rect
			(start -0.5842 1.3335)
			(end 0.5842 -1.3335)
			(stroke
				(width 0)
				(type default)
			)
			(fill no)
			(layer "F.CrtYd")
		)
		(fp_rect
			(start -0.5842 1.3335)
			(end 0.5842 -1.3335)
			(stroke
				(width 0)
				(type default)
			)
			(fill no)
			(layer "F.Fab")
		)
		(pad "1" smd custom
			(at 0 -0.762)
			(size 0.2159 0.2159)
			(layers "F.Cu" "F.Mask" "F.Paste")
			(net "P5V_A_2")
			(options
				(clearance outline)
				(anchor circle)
			)
			(primitives
				(gr_poly
					(pts
						(arc
							(start -0.3302 -0.4318)
							(mid -0.402042 -0.402042)
							(end -0.4318 -0.3302)
						)
						(arc
							(start -0.4318 0.3302)
							(mid -0.402042 0.402042)
							(end -0.3302 0.4318)
						)
						(arc
							(start 0.3302 0.4318)
							(mid 0.402042 0.402042)
							(end 0.4318 0.3302)
						)
						(arc
							(start 0.4318 -0.3302)
							(mid 0.402042 -0.402042)
							(end 0.3302 -0.4318)
						)
					)
					(width 0)
					(fill yes)
				)
			)
		)
		(pad "2" smd custom
			(at 0 0.762)
			(size 0.2159 0.2159)
			(layers "F.Cu" "F.Mask" "F.Paste")
			(net "FLT_HDD16")
			(options
				(clearance outline)
				(anchor circle)
			)
			(primitives
				(gr_poly
					(pts
						(arc
							(start -0.3302 -0.4318)
							(mid -0.402042 -0.402042)
							(end -0.4318 -0.3302)
						)
						(arc
							(start -0.4318 0.3302)
							(mid -0.402042 0.402042)
							(end -0.3302 0.4318)
						)
						(arc
							(start 0.3302 0.4318)
							(mid 0.402042 0.402042)
							(end 0.4318 0.3302)
						)
						(arc
							(start 0.4318 -0.3302)
							(mid 0.402042 -0.402042)
							(end 0.3302 -0.4318)
						)
					)
					(width 0)
					(fill yes)
				)
			)
		)
	)
	(footprint ""
		(layer "F.Cu")
		(at 280.055066 20.945348 -90)
		(property "Reference" "R1135"
			(at 0 0 270)
			(layer "F.SilkS")
			(hide yes)
			(effects
				(font
					(size 1.27 1.27)
				)
			)
		)
		(property "Value" "750R2F-GP"
			(at 0.064008 -3.993896 270)
			(unlocked yes)
			(layer "F.Fab")
			(hide yes)
			(effects
				(font
					(size 1.016 1.016)
					(thickness 0.1524)
				)
			)
		)
		(property "Device Type" "R402H16"
			(at 0.064008 -5.517896 270)
			(unlocked yes)
			(layer "F.Fab")
			(hide yes)
			(effects
				(font
					(size 1.016 1.016)
					(thickness 0.1524)
				)
			)
		)
		(duplicate_pad_numbers_are_jumpers no)
		(fp_line
			(start -0.508 -0.9398)
			(end -0.508 0.9398)
			(stroke
				(width 0.1524)
				(type default)
			)
			(layer "F.SilkS")
		)
		(fp_line
			(start 0.508 -0.9398)
			(end -0.508 -0.9398)
			(stroke
				(width 0.1524)
				(type default)
			)
			(layer "F.SilkS")
		)
		(fp_rect
			(start -0.508 0.9398)
			(end 0.508 -0.9398)
			(stroke
				(width 0)
				(type default)
			)
			(fill no)
			(layer "F.CrtYd")
		)
		(fp_rect
			(start -0.508 0.9398)
			(end 0.508 -0.9398)
			(stroke
				(width 0)
				(type default)
			)
			(fill no)
			(layer "F.Fab")
		)
		(pad "1" smd custom
			(at 0 -0.4445 270)
			(size 0.1397 0.1397)
			(layers "F.Cu" "F.Mask" "F.Paste")
			(net "DPB_PWR_BTN_A")
			(options
				(clearance outline)
				(anchor circle)
			)
			(primitives
				(gr_poly
					(pts
						(arc
							(start -0.1778 -0.2794)
							(mid -0.249642 -0.249642)
							(end -0.2794 -0.1778)
						)
						(arc
							(start -0.2794 0.1778)
							(mid -0.249642 0.249642)
							(end -0.1778 0.2794)
						)
						(arc
							(start 0.1778 0.2794)
							(mid 0.249642 0.249642)
							(end 0.2794 0.1778)
						)
						(arc
							(start 0.2794 -0.1778)
							(mid 0.249642 -0.249642)
							(end 0.1778 -0.2794)
						)
					)
					(width 0)
					(fill yes)
				)
			)
		)
		(pad "2" smd custom
			(at 0 0.4445 270)
			(size 0.1397 0.1397)
			(layers "F.Cu" "F.Mask" "F.Paste")
			(net "GND")
			(options
				(clearance outline)
				(anchor circle)
			)
			(primitives
				(gr_poly
					(pts
						(arc
							(start -0.1778 -0.2794)
							(mid -0.249642 -0.249642)
							(end -0.2794 -0.1778)
						)
						(arc
							(start -0.2794 0.1778)
							(mid -0.249642 0.249642)
							(end -0.1778 0.2794)
						)
						(arc
							(start 0.1778 0.2794)
							(mid 0.249642 0.249642)
							(end 0.2794 0.1778)
						)
						(arc
							(start 0.2794 -0.1778)
							(mid 0.249642 -0.249642)
							(end 0.1778 -0.2794)
						)
					)
					(width 0)
					(fill yes)
				)
			)
		)
	)
	(footprint ""
		(layer "F.Cu")
		(at 396.72895 -168.380918 -90)
		(property "Reference" "Q119"
			(at 0 0 270)
			(layer "F.SilkS")
			(hide yes)
			(effects
				(font
					(size 1.27 1.27)
				)
			)
		)
		(property "Value" "AO4406AL-GP"
			(at -3.707384 -1.5367 270)
			(unlocked yes)
			(layer "F.Fab")
			(hide yes)
			(effects
				(font
					(size 1.016 1.016)
					(thickness 0.1524)
				)
			)
		)
		(property "Device Type" "SOIC8H69"
			(at -3.707384 -3.0607 270)
			(unlocked yes)
			(layer "F.Fab")
			(hide yes)
			(effects
				(font
					(size 1.016 1.016)
					(thickness 0.1524)
				)
			)
		)
		(duplicate_pad_numbers_are_jumpers no)
		(fp_line
			(start -2.6289 3.4417)
			(end -2.6289 1.4732)
			(stroke
				(width 0.381)
				(type default)
			)
			(layer "F.SilkS")
		)
		(fp_line
			(start -2.7432 1.4224)
			(end -2.6416 1.4224)
			(stroke
				(width 0.1524)
				(type default)
			)
			(layer "F.SilkS")
		)
		(fp_line
			(start -2.7432 1.4224)
			(end 2.1336 1.4224)
			(stroke
				(width 0.1524)
				(type default)
			)
			(layer "F.SilkS")
		)
		(fp_line
			(start 2.1336 1.4224)
			(end 2.1336 -1.4224)
			(stroke
				(width 0.1524)
				(type default)
			)
			(layer "F.SilkS")
		)
		(fp_line
			(start -2.1844 -0.0508)
			(end -2.7178 0.508)
			(stroke
				(width 0.1524)
				(type default)
			)
			(layer "F.SilkS")
		)
		(fp_line
			(start -2.7178 -0.508)
			(end -2.1844 -0.0508)
			(stroke
				(width 0.1524)
				(type default)
			)
			(layer "F.SilkS")
		)
		(fp_line
			(start -2.7432 -1.4224)
			(end -2.7432 1.4224)
			(stroke
				(width 0.1524)
				(type default)
			)
			(layer "F.SilkS")
		)
		(fp_line
			(start 2.1336 -1.4224)
			(end -2.7432 -1.4224)
			(stroke
				(width 0.1524)
				(type default)
			)
			(layer "F.SilkS")
		)
		(fp_poly
			(pts
				(xy -2.2098 -1.4224) (xy -2.2098 1.4224) (xy 2.2098 1.4224) (xy 2.2098 -1.4224)
			)
			(stroke
				(width 0)
				(type default)
			)
			(fill yes)
			(layer "F.SilkS")
		)
		(fp_rect
			(start -2.450084 2.999994)
			(end 2.450084 -2.999994)
			(stroke
				(width 0)
				(type default)
			)
			(fill no)
			(layer "F.CrtYd")
		)
		(fp_poly
			(pts
				(xy -2.8194 3.6322) (xy -2.8194 -3.6322) (xy 2.8194 -3.6322) (xy 2.8194 1.18364) (xy 2.450084 1.18364)
				(xy 2.450084 -2.999994) (xy -2.450084 -2.999994) (xy -2.450084 2.999994) (xy 2.450084 2.999994)
				(xy 2.450084 1.18618) (xy 2.8194 1.18618) (xy 2.8194 3.6322)
			)
			(stroke
				(width 0)
				(type default)
			)
			(fill no)
			(layer "F.CrtYd")
		)
		(fp_rect
			(start -2.8194 3.6322)
			(end 2.8194 -3.6322)
			(stroke
				(width 0)
				(type default)
			)
			(fill no)
			(layer "F.Fab")
		)
		(pad "1" smd rect
			(at -1.905 2.54 270)
			(size 0.635 1.651)
			(layers "F.Cu" "F.Mask" "F.Paste")
			(net "P5V_HDD20")
		)
		(pad "2" smd rect
			(at -0.635 2.54 270)
			(size 0.635 1.651)
			(layers "F.Cu" "F.Mask" "F.Paste")
			(net "P5V_HDD20")
		)
		(pad "3" smd rect
			(at 0.635 2.54 270)
			(size 0.635 1.651)
			(layers "F.Cu" "F.Mask" "F.Paste")
			(net "P5V_HDD20")
		)
		(pad "4" smd rect
			(at 1.905 2.54 270)
			(size 0.635 1.651)
			(layers "F.Cu" "F.Mask" "F.Paste")
			(net "SW_HDD_P20")
		)
		(pad "5" smd rect
			(at 1.905 -2.54 270)
			(size 0.635 1.651)
			(layers "F.Cu" "F.Mask" "F.Paste")
			(net "P5V_A_3")
		)
		(pad "6" smd rect
			(at 0.635 -2.54 270)
			(size 0.635 1.651)
			(layers "F.Cu" "F.Mask" "F.Paste")
			(net "P5V_A_3")
		)
		(pad "7" smd rect
			(at -0.635 -2.54 270)
			(size 0.635 1.651)
			(layers "F.Cu" "F.Mask" "F.Paste")
			(net "P5V_A_3")
		)
		(pad "8" smd rect
			(at -1.905 -2.54 270)
			(size 0.635 1.651)
			(layers "F.Cu" "F.Mask" "F.Paste")
			(net "P5V_A_3")
		)
	)
)
